# T6G (Grand Teton) — schematic netlist excerpt (pin names and nets, part order shuffled) for the footprints in the layout excerpt that follows; sources: Cadence DE-HDL packaged netlist, KiCad conversion of 04192023_DAF0TMB3IC0_F0TG_MB_C_brd_V02_OCP.brd

J77  PICOPROBE_BXA  DELTA-L 4.0 EMPTY  pkg TRIANG_LAUNCH_3PXB  page 229
  \1_p\  = DELTA_L_85_10INCH_IN1_DP
  \2_n\  = DELTA_L_85_10INCH_IN1_DN
  \3_g\  = DELTA_L_GND_1

(kicad_pcb
	(version 20260206)
	(generator "pcbnew")
	(generator_version "10.0")
	(general
		(thickness 1.6)
		(legacy_teardrops no)
	)
	(paper "A4")
	(title_block
		(title "04192023_DAF0TMB3IC0_F0TG_MB_C_brd_V02_OCP.brd")
		(comment 1 "Grand Teton / footprints 393-393 of 8354")
	)
	(layers
		(0 "F.Cu" signal "TOP")
		(4 "In1.Cu" signal "GND")
		(6 "In2.Cu" signal "IN1")
		(8 "In3.Cu" signal "GND1")
		(10 "In4.Cu" signal "IN2")
		(12 "In5.Cu" signal "GND2")
		(14 "In6.Cu" signal "IN3")
		(16 "In7.Cu" signal "GND3")
		(18 "In8.Cu" signal "VCC")
		(20 "In9.Cu" signal "VCC1")
		(22 "In10.Cu" signal "GND4")
		(24 "In11.Cu" signal "IN4")
		(26 "In12.Cu" signal "GND5")
		(28 "In13.Cu" signal "IN5")
		(30 "In14.Cu" signal "GND6")
		(32 "In15.Cu" signal "IN6")
		(34 "In16.Cu" signal "GND7")
		(2 "B.Cu" signal "BOTTOM")
		(9 "F.Adhes" user "F.Adhesive")
		(11 "B.Adhes" user "B.Adhesive")
		(13 "F.Paste" user "Package Geometry/Pastemask Top")
		(15 "B.Paste" user "Package Geometry/Pastemask Bottom")
		(5 "F.SilkS" user "Ref Des/Silkscreen Top")
		(7 "B.SilkS" user "Ref Des/Silkscreen Bottom")
		(1 "F.Mask" user "Board Geometry/Soldermask Top")
		(3 "B.Mask" user "Board Geometry/Soldermask Bottom")
		(17 "Dwgs.User" user "User.Drawings")
		(19 "Cmts.User" user "User.Comments")
		(21 "Eco1.User" user "User.Eco1")
		(23 "Eco2.User" user "User.Eco2")
		(25 "Edge.Cuts" user "Board Geometry/Outline")
		(27 "Margin" user)
		(31 "F.CrtYd" user "Package Geometry/Place Bound Top")
		(29 "B.CrtYd" user "Package Geometry/Place Bound Bottom")
		(35 "F.Fab" user "Ref Des/Assembly Top")
		(33 "B.Fab" user "Ref Des/Assembly Bottom")
	)
	(footprint ""
		(layer "F.Cu")
		(at 97.795842 6.063234)
		(property "Reference" "J77"
			(at 5.390642 -0.182626 0)
			(unlocked yes)
			(layer "F.SilkS")
			(effects
				(font
					(size 0.7874 0.5842)
					(thickness 0.1524)
				)
				(justify left)
			)
		)
		(property "Value" ""
			(at 0 0 0)
			(layer "F.Fab")
			(effects
				(font
					(size 1.27 1.27)
				)
			)
		)
		(duplicate_pad_numbers_are_jumpers no)
		(fp_line
			(start -1.2192 -2.06756)
			(end 1.2192 -2.06756)
			(stroke
				(width 0.1524)
				(type default)
			)
			(layer "F.SilkS")
		)
		(fp_line
			(start -1.2192 2.06756)
			(end -1.2192 -2.06756)
			(stroke
				(width 0.1524)
				(type default)
			)
			(layer "F.SilkS")
		)
		(fp_line
			(start 1.2192 -2.06756)
			(end 1.2192 2.06756)
			(stroke
				(width 0.1524)
				(type default)
			)
			(layer "F.SilkS")
		)
		(fp_line
			(start 1.2192 2.06756)
			(end -1.2192 2.06756)
			(stroke
				(width 0.1524)
				(type default)
			)
			(layer "F.SilkS")
		)
		(pad "" np_thru_hole circle
			(at -2.8829 -1.27 270)
			(size 1.0414 1.0414)
			(drill 1.0414)
			(layers "*.Cu" "*.Mask")
			(clearance 0.381)
			(thermal_gap 0.381)
		)
		(pad "" np_thru_hole circle
			(at -2.8829 1.27 270)
			(size 1.0414 1.0414)
			(drill 1.0414)
			(layers "*.Cu" "*.Mask")
			(clearance 0.381)
			(thermal_gap 0.381)
		)
		(pad "" np_thru_hole circle
			(at 3.4671 -1.27 270)
			(size 1.0414 1.0414)
			(drill 1.0414)
			(layers "*.Cu" "*.Mask")
			(clearance 0.381)
			(thermal_gap 0.381)
		)
		(pad "" np_thru_hole circle
			(at 3.4671 1.27 270)
			(size 1.0414 1.0414)
			(drill 1.0414)
			(layers "*.Cu" "*.Mask")
			(clearance 0.381)
			(thermal_gap 0.381)
		)
		(pad "1" smd rect
			(at 0.8255 -0.249936 270)
			(size 0.3048 0.508)
			(layers "F.Cu" "F.Mask" "F.Paste")
			(net "DELTA_L_85_10INCH_IN1_DP")
		)
		(pad "2" smd rect
			(at 0.8255 0.249936 270)
			(size 0.3048 0.508)
			(layers "F.Cu" "F.Mask" "F.Paste")
			(net "DELTA_L_85_10INCH_IN1_DN")
		)
		(pad "3" smd circle
			(at 0 0)
			(size 0 0)
			(layers "F.Cu" "F.Mask" "F.Paste")
			(net "DELTA_L_GND_1")
		)
		(zone
			(layer "F.Cu")
			(hatch none 0.5)
			(connect_pads
				(clearance 0)
			)
			(min_thickness 0.25)
			(keepout
				(tracks not_allowed)
				(vias allowed)
				(pads allowed)
				(copperpour not_allowed)
				(footprints allowed)
			)
			(placement
				(enabled no)
				(sheetname "")
			)
			(fill
				(thermal_gap 0.5)
				(thermal_bridge_width 0.5)
				(island_removal_mode 0)
			)
			(polygon
				(pts
					(xy 98.913442 5.514594) (xy 98.913442 5.610098) (xy 98.316542 5.610098) (xy 98.316542 6.016498)
					(xy 98.913442 6.016498) (xy 98.913442 6.10997) (xy 98.316542 6.10997) (xy 98.316542 6.51637) (xy 98.913442 6.51637)
					(xy 98.913442 6.611874) (xy 98.214942 6.611874) (xy 98.214942 5.514594)
				)
			)
		)
		(zone
			(layers "F.Cu" "B.Cu" "In1.Cu" "In2.Cu" "In3.Cu" "In4.Cu" "In5.Cu" "In6.Cu"
				"In7.Cu" "In8.Cu" "In9.Cu" "In10.Cu" "In11.Cu" "In12.Cu" "In13.Cu" "In14.Cu"
				"In15.Cu" "In16.Cu"
			)
			(hatch none 0.5)
			(connect_pads
				(clearance 0)
			)
			(min_thickness 0.25)
			(keepout
				(tracks not_allowed)
				(vias allowed)
				(pads allowed)
				(copperpour not_allowed)
				(footprints allowed)
			)
			(placement
				(enabled no)
				(sheetname "")
			)
			(fill
				(thermal_gap 0.5)
				(thermal_bridge_width 0.5)
				(island_removal_mode 0)
			)
			(polygon
				(pts
					(arc
						(start 95.840042 4.793234)
						(mid 93.985842 4.793234)
						(end 95.840042 4.793234)
					)
				)
			)
		)
		(zone
			(layers "F.Cu" "B.Cu" "In1.Cu" "In2.Cu" "In3.Cu" "In4.Cu" "In5.Cu" "In6.Cu"
				"In7.Cu" "In8.Cu" "In9.Cu" "In10.Cu" "In11.Cu" "In12.Cu" "In13.Cu" "In14.Cu"
				"In15.Cu" "In16.Cu"
			)
			(hatch none 0.5)
			(connect_pads
				(clearance 0)
			)
			(min_thickness 0.25)
			(keepout
				(tracks not_allowed)
				(vias allowed)
				(pads allowed)
				(copperpour not_allowed)
				(footprints allowed)
			)
			(placement
				(enabled no)
				(sheetname "")
			)
			(fill
				(thermal_gap 0.5)
				(thermal_bridge_width 0.5)
				(island_removal_mode 0)
			)
			(polygon
				(pts
					(arc
						(start 95.840042 7.333234)
						(mid 93.985842 7.333234)
						(end 95.840042 7.333234)
					)
				)
			)
		)
		(zone
			(layers "F.Cu" "B.Cu" "In1.Cu" "In2.Cu" "In3.Cu" "In4.Cu" "In5.Cu" "In6.Cu"
				"In7.Cu" "In8.Cu" "In9.Cu" "In10.Cu" "In11.Cu" "In12.Cu" "In13.Cu" "In14.Cu"
				"In15.Cu" "In16.Cu"
			)
			(hatch none 0.5)
			(connect_pads
				(clearance 0)
			)
			(min_thickness 0.25)
			(keepout
				(tracks not_allowed)
				(vias allowed)
				(pads allowed)
				(copperpour not_allowed)
				(footprints allowed)
			)
			(placement
				(enabled no)
				(sheetname "")
			)
			(fill
				(thermal_gap 0.5)
				(thermal_bridge_width 0.5)
				(island_removal_mode 0)
			)
			(polygon
				(pts
					(arc
						(start 102.190042 4.793234)
						(mid 100.335842 4.793234)
						(end 102.190042 4.793234)
					)
				)
			)
		)
		(zone
			(layers "F.Cu" "B.Cu" "In1.Cu" "In2.Cu" "In3.Cu" "In4.Cu" "In5.Cu" "In6.Cu"
				"In7.Cu" "In8.Cu" "In9.Cu" "In10.Cu" "In11.Cu" "In12.Cu" "In13.Cu" "In14.Cu"
				"In15.Cu" "In16.Cu"
			)
			(hatch none 0.5)
			(connect_pads
				(clearance 0)
			)
			(min_thickness 0.25)
			(keepout
				(tracks not_allowed)
				(vias allowed)
				(pads allowed)
				(copperpour not_allowed)
				(footprints allowed)
			)
			(placement
				(enabled no)
				(sheetname "")
			)
			(fill
				(thermal_gap 0.5)
				(thermal_bridge_width 0.5)
				(island_removal_mode 0)
			)
			(polygon
				(pts
					(arc
						(start 102.190042 7.333234)
						(mid 100.335842 7.333234)
						(end 102.190042 7.333234)
					)
				)
			)
		)
	)
)
